(kicad_pcb
	(version 20241229)
	(generator "pcbnew")
	(generator_version "9.0")
	(general
		(thickness 1.6296)
		(legacy_teardrops no)
	)
	(paper "A3")
	(title_block
		(title "Thunderbolt to 10GbE adapter")
		(date "2026-04-21")
		(rev "1.1.0")
		(company "Antmicro Ltd")
		(comment 1 "www.antmicro.com")
		(comment 9 "footprints 322-326 of 703")
	)
	(layers
		(0 "F.Cu" signal)
		(4 "In1.Cu" signal)
		(6 "In2.Cu" signal)
		(8 "In3.Cu" signal)
		(10 "In4.Cu" signal)
		(12 "In5.Cu" signal)
		(14 "In6.Cu" signal)
		(2 "B.Cu" signal)
		(9 "F.Adhes" user "F.Adhesive")
		(11 "B.Adhes" user "B.Adhesive")
		(13 "F.Paste" user)
		(15 "B.Paste" user)
		(5 "F.SilkS" user "F.Silkscreen")
		(7 "B.SilkS" user "B.Silkscreen")
		(1 "F.Mask" user)
		(3 "B.Mask" user)
		(17 "Dwgs.User" user "User.Drawings")
		(19 "Cmts.User" user "User.Comments")
		(21 "Eco1.User" user "User.Eco1")
		(23 "Eco2.User" user "User.Eco2")
		(25 "Edge.Cuts" user)
		(27 "Margin" user)
		(31 "F.CrtYd" user "F.Courtyard")
		(29 "B.CrtYd" user "B.Courtyard")
		(35 "F.Fab" user)
		(33 "B.Fab" user)
	)
	(footprint "antmicro-footprints:C_0603_1608Metric_EIA"
		(layer "F.Cu")
		(at 139.500001 113)
		(descr "Capacitor SMD 0603, IPC-7351 Density Level A")
		(tags "Capacitor 0603")
		(property "Reference" "C110"
			(at 16 16.799998 0)
			(layer "F.SilkS")
			(effects
				(font
					(size 0.7 0.7)
					(thickness 0.15)
				)
			)
		)
		(property "Value" "C_22u_16V_0603"
			(at -1.42757 1.770288 0)
			(layer "F.Fab")
			(effects
				(font
					(size 0.7 0.7)
					(thickness 0.15)
				)
				(justify left bottom)
			)
		)
		(property "Datasheet" "https://product.samsungsem.com/mlcc/CL10A226MO7JZN.do"
			(at 0 0 0)
			(layer "F.Fab")
			(hide yes)
			(effects
				(font
					(size 1.27 1.27)
					(thickness 0.15)
				)
			)
		)
		(property "Description" "SMD Multilayer Ceramic Capacitor"
			(at 0 0 0)
			(layer "F.Fab")
			(hide yes)
			(effects
				(font
					(size 1.27 1.27)
					(thickness 0.15)
				)
			)
		)
		(property "MPN" "CL10A226MO7JZNC"
			(at 0 0 0)
			(unlocked yes)
			(layer "F.Fab")
			(hide yes)
			(effects
				(font
					(size 1 1)
					(thickness 0.15)
				)
			)
		)
		(property "Manufacturer" "Samsung Electro-Mechanics"
			(at 0 0 0)
			(unlocked yes)
			(layer "F.Fab")
			(hide yes)
			(effects
				(font
					(size 1 1)
					(thickness 0.15)
				)
			)
		)
		(property "License" "Apache-2.0"
			(at 0 0 0)
			(unlocked yes)
			(layer "F.Fab")
			(hide yes)
			(effects
				(font
					(size 1 1)
					(thickness 0.15)
				)
			)
		)
		(property "Author" "Antmicro"
			(at 0 0 0)
			(unlocked yes)
			(layer "F.Fab")
			(hide yes)
			(effects
				(font
					(size 1 1)
					(thickness 0.15)
				)
			)
		)
		(property "Val" "22u"
			(at 0 0 0)
			(unlocked yes)
			(layer "F.Fab")
			(hide yes)
			(effects
				(font
					(size 1 1)
					(thickness 0.15)
				)
			)
		)
		(property "Voltage" "16V"
			(at 0 0 0)
			(unlocked yes)
			(layer "F.Fab")
			(hide yes)
			(effects
				(font
					(size 1 1)
					(thickness 0.15)
				)
			)
		)
		(property "Dielectric" ""
			(at 0 0 0)
			(unlocked yes)
			(layer "F.Fab")
			(hide yes)
			(effects
				(font
					(size 1 1)
					(thickness 0.15)
				)
			)
		)
		(sheetname "/X710 DCDC converters/")
		(sheetfile "DCDC_converters_X710.kicad_sch")
		(attr smd)
		(fp_line
			(start -0.15 -0.55)
			(end 0.15 -0.55)
			(stroke
				(width 0.15)
				(type solid)
			)
			(layer "F.SilkS")
		)
		(fp_line
			(start -0.15 0.55)
			(end 0.15 0.55)
			(stroke
				(width 0.15)
				(type solid)
			)
			(layer "F.SilkS")
		)
		(fp_rect
			(start -1.25 -0.65)
			(end 1.25 0.65)
			(stroke
				(width 0.05)
				(type solid)
			)
			(fill no)
			(layer "F.CrtYd")
		)
		(fp_rect
			(start -0.8 -0.45)
			(end 0.8 0.45)
			(stroke
				(width 0.15)
				(type solid)
			)
			(fill no)
			(layer "F.Fab")
		)
		(fp_text user "${REFERENCE}"
			(at -1.682 3.895 0)
			(layer "F.Fab")
			(effects
				(font
					(size 0.7 0.7)
					(thickness 0.15)
				)
				(justify left bottom)
			)
		)
		(fp_text user "License: Apache-2.0"
			(at -1.682 5.895 0)
			(layer "F.Fab")
			(effects
				(font
					(size 0.7 0.7)
					(thickness 0.15)
				)
				(justify left bottom)
			)
		)
		(fp_text user "Author: Antmicro"
			(at -1.682 4.894 0)
			(layer "F.Fab")
			(effects
				(font
					(size 0.7 0.7)
					(thickness 0.15)
				)
				(justify left bottom)
			)
		)
		(pad "1" smd roundrect
			(at -0.7 0)
			(size 0.8 1.1)
			(layers "F.Cu" "F.Mask" "F.Paste")
			(roundrect_rratio 0.2)
			(net 23 "GND")
			(pintype "passive")
		)
		(pad "2" smd roundrect
			(at 0.7 0)
			(size 0.8 1.1)
			(layers "F.Cu" "F.Mask" "F.Paste")
			(roundrect_rratio 0.2)
			(net 40 "+5V")
			(pintype "passive")
		)
	)
	(footprint "antmicro-footprints:R_0402_1005Metric"
		(layer "F.Cu")
		(at 159 46.3 -90)
		(descr "Resistor SMD 0402")
		(tags "resistor SMD 0402")
		(property "Reference" "R229"
			(at 1.9 -6.3 270)
			(layer "F.SilkS")
			(effects
				(font
					(size 0.7 0.7)
					(thickness 0.15)
				)
				(justify left bottom)
			)
		)
		(property "Value" "R_200k_0402"
			(at -1.011843 1.772047 270)
			(layer "F.Fab")
			(effects
				(font
					(size 0.7 0.7)
					(thickness 0.15)
				)
				(justify left bottom)
			)
		)
		(property "Datasheet" "https://www.bourns.com/docs/product-datasheets/cr.pdf"
			(at 0 0 270)
			(layer "F.Fab")
			(hide yes)
			(effects
				(font
					(size 1.27 1.27)
					(thickness 0.15)
				)
			)
		)
		(property "Description" "SMD Chip Resistor, 200 kohm, ± 1%, 62.5 mW, 0402 [1005 Metric], Thick Film, General Purpose"
			(at 0 0 270)
			(layer "F.Fab")
			(hide yes)
			(effects
				(font
					(size 1.27 1.27)
					(thickness 0.15)
				)
			)
		)
		(property "MPN" "CR0402-FX-2003GLF"
			(at 0 0 270)
			(unlocked yes)
			(layer "F.Fab")
			(hide yes)
			(effects
				(font
					(size 1 1)
					(thickness 0.15)
				)
			)
		)
		(property "Manufacturer" "Bourns"
			(at 0 0 270)
			(unlocked yes)
			(layer "F.Fab")
			(hide yes)
			(effects
				(font
					(size 1 1)
					(thickness 0.15)
				)
			)
		)
		(property "License" "Apache-2.0"
			(at 0 0 270)
			(unlocked yes)
			(layer "F.Fab")
			(hide yes)
			(effects
				(font
					(size 1 1)
					(thickness 0.15)
				)
			)
		)
		(property "Author" "Antmicro"
			(at 0 0 270)
			(unlocked yes)
			(layer "F.Fab")
			(hide yes)
			(effects
				(font
					(size 1 1)
					(thickness 0.15)
				)
			)
		)
		(property "Val" "200k"
			(at 0 0 270)
			(unlocked yes)
			(layer "F.Fab")
			(hide yes)
			(effects
				(font
					(size 1 1)
					(thickness 0.15)
				)
			)
		)
		(property "Tolerance" "1%"
			(at 0 0 270)
			(unlocked yes)
			(layer "F.Fab")
			(hide yes)
			(effects
				(font
					(size 1 1)
					(thickness 0.15)
				)
			)
		)
		(sheetname "/Power input/")
		(sheetfile "power_input.kicad_sch")
		(attr smd)
		(fp_rect
			(start -0.925 -0.47)
			(end 0.925 0.47)
			(stroke
				(width 0.05)
				(type default)
			)
			(fill no)
			(layer "F.CrtYd")
		)
		(fp_rect
			(start -0.5 -0.25)
			(end 0.5 0.25)
			(stroke
				(width 0.15)
				(type solid)
			)
			(fill no)
			(layer "F.Fab")
		)
		(fp_text user "License: Apache-2.0"
			(at -0.95 5.169 270)
			(layer "F.Fab")
			(effects
				(font
					(size 0.7 0.7)
					(thickness 0.15)
				)
				(justify left bottom)
			)
		)
		(fp_text user "${REFERENCE}"
			(at -0.95 3.168 270)
			(layer "F.Fab")
			(effects
				(font
					(size 0.7 0.7)
					(thickness 0.15)
				)
				(justify left bottom)
			)
		)
		(fp_text user "Author: Antmicro"
			(at -0.95 4.169 270)
			(layer "F.Fab")
			(effects
				(font
					(size 0.7 0.7)
					(thickness 0.15)
				)
				(justify left bottom)
			)
		)
		(pad "1" smd roundrect
			(at -0.48 0 270)
			(size 0.59 0.64)
			(layers "F.Cu" "F.Mask" "F.Paste")
			(roundrect_rratio 0.25)
			(net 23 "GND")
			(pintype "passive")
		)
		(pad "2" smd roundrect
			(at 0.48 0 270)
			(size 0.59 0.64)
			(layers "F.Cu" "F.Mask" "F.Paste")
			(roundrect_rratio 0.25)
			(net 389 "/Power input/5V_MODE1")
			(pintype "passive")
		)
	)
	(footprint "antmicro-footprints:R_0402_1005Metric"
		(layer "F.Cu")
		(at 117 68.9)
		(descr "Resistor SMD 0402")
		(tags "resistor SMD 0402")
		(property "Reference" "R219"
			(at 3.6 -10.5 0)
			(layer "F.SilkS")
			(effects
				(font
					(size 0.7 0.7)
					(thickness 0.15)
				)
				(justify left bottom)
			)
		)
		(property "Value" "R_1k_0402"
			(at -1.011843 1.772047 0)
			(layer "F.Fab")
			(effects
				(font
					(size 0.7 0.7)
					(thickness 0.15)
				)
				(justify left bottom)
			)
		)
		(property "Datasheet" "https://www.bourns.com/docs/product-datasheets/cr.pdf"
			(at 0 0 0)
			(layer "F.Fab")
			(hide yes)
			(effects
				(font
					(size 1.27 1.27)
					(thickness 0.15)
				)
			)
		)
		(property "Description" "SMD Chip Resistor, 1 kohm, ± 1%, 63 mW, 0402 [1005 Metric], Thick Film, General Purpose"
			(at 0 0 0)
			(layer "F.Fab")
			(hide yes)
			(effects
				(font
					(size 1.27 1.27)
					(thickness 0.15)
				)
			)
		)
		(property "MPN" "CR0402-FX-1001GLF"
			(at 0 0 0)
			(unlocked yes)
			(layer "F.Fab")
			(hide yes)
			(effects
				(font
					(size 1 1)
					(thickness 0.15)
				)
			)
		)
		(property "Manufacturer" "Bourns"
			(at 0 0 0)
			(unlocked yes)
			(layer "F.Fab")
			(hide yes)
			(effects
				(font
					(size 1 1)
					(thickness 0.15)
				)
			)
		)
		(property "License" "Apache-2.0"
			(at 0 0 0)
			(unlocked yes)
			(layer "F.Fab")
			(hide yes)
			(effects
				(font
					(size 1 1)
					(thickness 0.15)
				)
			)
		)
		(property "Author" "Antmicro"
			(at 0 0 0)
			(unlocked yes)
			(layer "F.Fab")
			(hide yes)
			(effects
				(font
					(size 1 1)
					(thickness 0.15)
				)
			)
		)
		(property "Val" "1k"
			(at 0 0 0)
			(unlocked yes)
			(layer "F.Fab")
			(hide yes)
			(effects
				(font
					(size 1 1)
					(thickness 0.15)
				)
			)
		)
		(property "Tolerance" "1%"
			(at 0 0 0)
			(unlocked yes)
			(layer "F.Fab")
			(hide yes)
			(effects
				(font
					(size 1 1)
					(thickness 0.15)
				)
			)
		)
		(sheetname "/Fan controller/")
		(sheetfile "fan-controller.kicad_sch")
		(attr smd)
		(fp_rect
			(start -0.925 -0.47)
			(end 0.925 0.47)
			(stroke
				(width 0.05)
				(type default)
			)
			(fill no)
			(layer "F.CrtYd")
		)
		(fp_rect
			(start -0.5 -0.25)
			(end 0.5 0.25)
			(stroke
				(width 0.15)
				(type solid)
			)
			(fill no)
			(layer "F.Fab")
		)
		(fp_text user "Author: Antmicro"
			(at -0.95 4.169 0)
			(layer "F.Fab")
			(effects
				(font
					(size 0.7 0.7)
					(thickness 0.15)
				)
				(justify left bottom)
			)
		)
		(fp_text user "License: Apache-2.0"
			(at -0.95 5.169 0)
			(layer "F.Fab")
			(effects
				(font
					(size 0.7 0.7)
					(thickness 0.15)
				)
				(justify left bottom)
			)
		)
		(fp_text user "${REFERENCE}"
			(at -0.95 3.168 0)
			(layer "F.Fab")
			(effects
				(font
					(size 0.7 0.7)
					(thickness 0.15)
				)
				(justify left bottom)
			)
		)
		(pad "1" smd roundrect
			(at -0.48 0)
			(size 0.59 0.64)
			(layers "F.Cu" "F.Mask" "F.Paste")
			(roundrect_rratio 0.25)
			(net 23 "GND")
			(pintype "passive")
		)
		(pad "2" smd roundrect
			(at 0.48 0)
			(size 0.59 0.64)
			(layers "F.Cu" "F.Mask" "F.Paste")
			(roundrect_rratio 0.25)
			(net 157 "/Fan controller/DMIN")
			(pintype "passive")
		)
	)
	(footprint "antmicro-footprints:R_0402_1005Metric"
		(layer "F.Cu")
		(at 127.084 87.77)
		(descr "Resistor SMD 0402")
		(tags "resistor SMD 0402")
		(property "Reference" "R118"
			(at -1.084 -0.509 0)
			(layer "F.SilkS")
			(effects
				(font
					(size 0.7 0.7)
					(thickness 0.15)
				)
				(justify left bottom)
			)
		)
		(property "Value" "R_8k2_0402"
			(at -1.011843 1.772047 0)
			(layer "F.Fab")
			(effects
				(font
					(size 0.7 0.7)
					(thickness 0.15)
				)
				(justify left bottom)
			)
		)
		(property "Datasheet" "https://www.bourns.com/docs/product-datasheets/cr.pdf"
			(at 0 0 0)
			(layer "F.Fab")
			(hide yes)
			(effects
				(font
					(size 1.27 1.27)
					(thickness 0.15)
				)
			)
		)
		(property "Description" "SMD Chip Resistor"
			(at 0 0 0)
			(layer "F.Fab")
			(hide yes)
			(effects
				(font
					(size 1.27 1.27)
					(thickness 0.15)
				)
			)
		)
		(property "MPN" "CR0402-FX-8201GLF"
			(at 0 0 0)
			(unlocked yes)
			(layer "F.Fab")
			(hide yes)
			(effects
				(font
					(size 1 1)
					(thickness 0.15)
				)
			)
		)
		(property "Manufacturer" "Bourns"
			(at 0 0 0)
			(unlocked yes)
			(layer "F.Fab")
			(hide yes)
			(effects
				(font
					(size 1 1)
					(thickness 0.15)
				)
			)
		)
		(property "License" "Apache-2.0"
			(at 0 0 0)
			(unlocked yes)
			(layer "F.Fab")
			(hide yes)
			(effects
				(font
					(size 1 1)
					(thickness 0.15)
				)
			)
		)
		(property "Author" "Antmicro"
			(at 0 0 0)
			(unlocked yes)
			(layer "F.Fab")
			(hide yes)
			(effects
				(font
					(size 1 1)
					(thickness 0.15)
				)
			)
		)
		(property "Val" "8k2"
			(at 0 0 0)
			(unlocked yes)
			(layer "F.Fab")
			(hide yes)
			(effects
				(font
					(size 1 1)
					(thickness 0.15)
				)
			)
		)
		(property "Tolerance" "1%"
			(at 0 0 0)
			(unlocked yes)
			(layer "F.Fab")
			(hide yes)
			(effects
				(font
					(size 1 1)
					(thickness 0.15)
				)
			)
		)
		(sheetname "/X710-AT2 PCIe/")
		(sheetfile "x710-at2-pcie.kicad_sch")
		(attr smd)
		(fp_rect
			(start -0.925 -0.47)
			(end 0.925 0.47)
			(stroke
				(width 0.05)
				(type default)
			)
			(fill no)
			(layer "F.CrtYd")
		)
		(fp_rect
			(start -0.5 -0.25)
			(end 0.5 0.25)
			(stroke
				(width 0.15)
				(type solid)
			)
			(fill no)
			(layer "F.Fab")
		)
		(fp_text user "License: Apache-2.0"
			(at -0.95 5.169 0)
			(layer "F.Fab")
			(effects
				(font
					(size 0.7 0.7)
					(thickness 0.15)
				)
				(justify left bottom)
			)
		)
		(fp_text user "Author: Antmicro"
			(at -0.95 4.169 0)
			(layer "F.Fab")
			(effects
				(font
					(size 0.7 0.7)
					(thickness 0.15)
				)
				(justify left bottom)
			)
		)
		(fp_text user "${REFERENCE}"
			(at -0.95 3.168 0)
			(layer "F.Fab")
			(effects
				(font
					(size 0.7 0.7)
					(thickness 0.15)
				)
				(justify left bottom)
			)
		)
		(pad "1" smd roundrect
			(at -0.48 0)
			(size 0.59 0.64)
			(layers "F.Cu" "F.Mask" "F.Paste")
			(roundrect_rratio 0.25)
			(net 4 "/X710-AT2 PCIe/PCIe_JTAG.JTMS")
			(pintype "passive")
		)
		(pad "2" smd roundrect
			(at 0.48 0)
			(size 0.59 0.64)
			(layers "F.Cu" "F.Mask" "F.Paste")
			(roundrect_rratio 0.25)
			(net 7 "+3V3")
			(pintype "passive")
		)
	)
	(footprint "antmicro-footprints:C_0603_1608Metric"
		(layer "F.Cu")
		(at 148.955 68.574999 -90)
		(descr "Capacitor SMD 0603")
		(tags "capacitor 0603")
		(property "Reference" "C215"
			(at -12.274999 -20.045 270)
			(layer "F.SilkS")
			(effects
				(font
					(size 0.7 0.7)
					(thickness 0.15)
				)
			)
		)
		(property "Value" "C_10u_10V_X7R_0603"
			(at -1.42757 1.770288 270)
			(layer "F.Fab")
			(effects
				(font
					(size 0.7 0.7)
					(thickness 0.15)
				)
				(justify left bottom)
			)
		)
		(property "Datasheet" "https://www.murata.com/products/productdetail?partno=GRM188Z71A106KA73%23"
			(at 0 0 270)
			(layer "F.Fab")
			(hide yes)
			(effects
				(font
					(size 1.27 1.27)
					(thickness 0.15)
				)
			)
		)
		(property "Description" "SMD Multilayer Ceramic Capacitor,  10µF, 10V, 0603, ±10%, X7R"
			(at 0 0 270)
			(layer "F.Fab")
			(hide yes)
			(effects
				(font
					(size 1.27 1.27)
					(thickness 0.15)
				)
			)
		)
		(property "MPN" "GRM188Z71A106KA73D"
			(at 0 0 270)
			(unlocked yes)
			(layer "F.Fab")
			(hide yes)
			(effects
				(font
					(size 1 1)
					(thickness 0.15)
				)
			)
		)
		(property "Val" "10u"
			(at 0 0 270)
			(unlocked yes)
			(layer "F.Fab")
			(hide yes)
			(effects
				(font
					(size 1 1)
					(thickness 0.15)
				)
			)
		)
		(property "Voltage" "10V"
			(at 0 0 270)
			(unlocked yes)
			(layer "F.Fab")
			(hide yes)
			(effects
				(font
					(size 1 1)
					(thickness 0.15)
				)
			)
		)
		(property "Dielectric" "X7R"
			(at 0 0 270)
			(unlocked yes)
			(layer "F.Fab")
			(hide yes)
			(effects
				(font
					(size 1 1)
					(thickness 0.15)
				)
			)
		)
		(property "Manufacturer" "Murata"
			(at 0 0 270)
			(unlocked yes)
			(layer "F.Fab")
			(hide yes)
			(effects
				(font
					(size 1 1)
					(thickness 0.15)
				)
			)
		)
		(property "License" "Apache-2.0"
			(at 0 0 270)
			(unlocked yes)
			(layer "F.Fab")
			(hide yes)
			(effects
				(font
					(size 1 1)
					(thickness 0.15)
				)
			)
		)
		(property "Author" "Antmicro"
			(at 0 0 270)
			(unlocked yes)
			(layer "F.Fab")
			(hide yes)
			(effects
				(font
					(size 1 1)
					(thickness 0.15)
				)
			)
		)
		(sheetname "/X710-AT2 power/")
		(sheetfile "x710-at2-power.kicad_sch")
		(attr smd)
		(fp_line
			(start -0.15 0.4)
			(end 0.15 0.4)
			(stroke
				(width 0.15)
				(type solid)
			)
			(layer "F.SilkS")
		)
		(fp_line
			(start -0.15 -0.4)
			(end 0.15 -0.4)
			(stroke
				(width 0.15)
				(type solid)
			)
			(layer "F.SilkS")
		)
		(fp_rect
			(start -1.25 -0.65)
			(end 1.25 0.65)
			(stroke
				(width 0.05)
				(type solid)
			)
			(fill no)
			(layer "F.CrtYd")
		)
		(fp_rect
			(start -0.8 -0.4)
			(end 0.8 0.4)
			(stroke
				(width 0.15)
				(type solid)
			)
			(fill no)
			(layer "F.Fab")
		)
		(fp_text user "License: Apache-2.0"
			(at -1.682 5.895 270)
			(layer "F.Fab")
			(effects
				(font
					(size 0.7 0.7)
					(thickness 0.15)
				)
				(justify left bottom)
			)
		)
		(fp_text user "${REFERENCE}"
			(at -1.682 3.895 270)
			(layer "F.Fab")
			(effects
				(font
					(size 0.7 0.7)
					(thickness 0.15)
				)
				(justify left bottom)
			)
		)
		(fp_text user "Author: Antmicro"
			(at -1.682 4.894 270)
			(layer "F.Fab")
			(effects
				(font
					(size 0.7 0.7)
					(thickness 0.15)
				)
				(justify left bottom)
			)
		)
		(pad "1" smd roundrect
			(at -0.7 0 270)
			(size 0.8 1)
			(layers "F.Cu" "F.Mask" "F.Paste")
			(roundrect_rratio 0.2)
			(net 23 "GND")
			(pintype "passive")
		)
		(pad "2" smd roundrect
			(at 0.7 0 270)
			(size 0.8 1)
			(layers "F.Cu" "F.Mask" "F.Paste")
			(roundrect_rratio 0.2)
			(net 7 "+3V3")
			(pintype "passive")
		)
	)
)
